# T6G (Grand Teton) — schematic netlist excerpt (pin names and nets, part order shuffled) for the footprints in the layout excerpt that follows; sources: Cadence DE-HDL packaged netlist, KiCad conversion of 04192023_DAF0TMB3IC0_F0TG_MB_C_brd_V02_OCP.brd

J15  SCONN288_DDR506112002KQ  IO  pkg DDR288S_1-1VXC  page 87
  VIN_BULK0  = P12V_MEM_CPU0
  RFU0  = NC
  VIN_MGMT  = P3V3_AUX
  HSCL  = I3C_SPD_DDRB_CPU0_SCL
  HSDA  = I3C_SPD_DDRB_CPU0_SDA
  VSS0  = GND
  DQ0_A  = M_B_CPU0_SA_DQ<0>
  VSS1  = GND
  DQ1_A  = M_B_CPU0_SA_DQ<1>
  VSS2  = GND
  DQS0_A_T  = M_B_CPU0_SA_DQS_DP<0>
  DQS0_A_C  = M_B_CPU0_SA_DQS_DN<0>
  VSS3  = GND
  DQ4_A  = M_B_CPU0_SA_DQ<4>
  VSS4  = GND
  DQ5_A  = M_B_CPU0_SA_DQ<5>
  VSS5  = GND
  DQ8_A  = M_B_CPU0_SA_DQ<8>
  VSS6  = GND
  DQ9_A  = M_B_CPU0_SA_DQ<9>
  VSS7  = GND
  DQS1_A_T  = M_B_CPU0_SA_DQS_DP<1>
  DQS1_A_C  = M_B_CPU0_SA_DQS_DN<1>
  VSS8  = GND
  DQ12_A  = M_B_CPU0_SA_DQ<12>
  VSS9  = GND
  DQ13_A  = M_B_CPU0_SA_DQ<13>
  VSS10  = GND
  DQ16_A  = M_B_CPU0_SA_DQ<16>
  VSS11  = GND
  DQ17_A  = M_B_CPU0_SA_DQ<17>
  VSS12  = GND
  DQS2_A_T  = M_B_CPU0_SA_DQS_DP<2>
  DQS2_A_C  = M_B_CPU0_SA_DQS_DN<2>
  VSS13  = GND
  DQ20_A  = M_B_CPU0_SA_DQ<20>
  VSS14  = GND
  DQ21_A  = M_B_CPU0_SA_DQ<21>
  VSS15  = GND
  DQ24_A  = M_B_CPU0_SA_DQ<24>
  VSS16  = GND
  DQ25_A  = M_B_CPU0_SA_DQ<25>
  VSS17  = GND
  DQS3_A_T  = M_B_CPU0_SA_DQS_DP<3>
  DQS3_A_C  = M_B_CPU0_SA_DQS_DN<3>
  VSS18  = GND
  DQ28_A  = M_B_CPU0_SA_DQ<28>
  VSS19  = GND
  DQ29_A  = M_B_CPU0_SA_DQ<29>
  VSS20  = GND
  CB0_A  = M_B_CPU0_SA_CB<0>
  VSS21  = GND
  CB1_A  = M_B_CPU0_SA_CB<1>
  VSS22  = GND
  DQS4_A_T  = M_B_CPU0_SA_DQS_DP<4>
  DQS4_A_C  = M_B_CPU0_SA_DQS_DN<4>
  VSS23  = GND
  CB4_A  = M_B_CPU0_SA_CB<4>
  VSS24  = GND
  CB5_A  = M_B_CPU0_SA_CB<5>
  VSS25  = GND
  ALERT_N  = M_B_CPU0_ALERT_N
  VSS26  = GND
  CS0_A_N  = M_B_CPU0_SA_CS_N<0>
  VSS27  = GND
  CA0_A  = M_B_CPU0_SA_CA<0>
  VSS28  = GND
  CA2_A  = M_B_CPU0_SA_CA<2>
  VSS29  = GND
  CA4_A  = M_B_CPU0_SA_CA<4>
  VSS30  = GND
  CA6_A  = M_B_CPU0_SA_CA<6>
  VSS31  = GND
  PAR_A  = M_B_CPU0_SA_PAR
  VSS32  = GND
  CA0_B  = M_B_CPU0_SB_CA<0>
  VSS33  = GND
  CA2_B  = M_B_CPU0_SB_CA<2>
  VSS34  = GND
  CA4_B  = M_B_CPU0_SB_CA<4>
  VSS35  = GND
  CA6_B  = M_B_CPU0_SB_CA<6>
  VSS36  = GND
  CS0_B_N  = M_B_CPU0_SB_CS_N<0>
  VSS37  = GND
  \lbd||rsp_a_n\  = M_B_CPU0_SA_RSP<0>
  \lbs||rsp_b_n\  = M_B_CPU0_SB_RSP<0>
  VSS38  = GND
  CB4_B  = M_B_CPU0_SB_CB<4>
  VSS39  = GND
  CB5_B  = M_B_CPU0_SB_CB<5>
  VSS40  = GND
  \dqs9_b_t||tdqs9_b_t||dbi4_b_n\  = M_B_CPU0_SB_DQS_DP<9>
  \dqs9_b_c||tdqs9_b_c\  = M_B_CPU0_SB_DQS_DN<9>
  VSS41  = GND
  CB0_B  = M_B_CPU0_SB_CB<0>
  VSS42  = GND
  CB1_B  = M_B_CPU0_SB_CB<1>
  VSS43  = GND
  DQ0_B  = M_B_CPU0_SB_DQ<0>
  VSS44  = GND
  DQ1_B  = M_B_CPU0_SB_DQ<1>
  VSS45  = GND
  DQS0_B_T  = M_B_CPU0_SB_DQS_DP<0>
  DQS0_B_C  = M_B_CPU0_SB_DQS_DN<0>
  VSS46  = GND
  DQ4_B  = M_B_CPU0_SB_DQ<4>
  VSS47  = GND
  DQ5_B  = M_B_CPU0_SB_DQ<5>
  VSS48  = GND
  DQ8_B  = M_B_CPU0_SB_DQ<8>
  VSS49  = GND
  DQ9_B  = M_B_CPU0_SB_DQ<9>
  VSS50  = GND
  DQS1_B_T  = M_B_CPU0_SB_DQS_DP<1>
  DQS1_B_C  = M_B_CPU0_SB_DQS_DN<1>
  VSS51  = GND
  DQ12_B  = M_B_CPU0_SB_DQ<12>
  VSS52  = GND
  DQ13_B  = M_B_CPU0_SB_DQ<13>
  VSS53  = GND
  DQ16_B  = M_B_CPU0_SB_DQ<16>
  VSS54  = GND
  DQ17_B  = M_B_CPU0_SB_DQ<17>
  VSS55  = GND
  DQS2_B_T  = M_B_CPU0_SB_DQS_DP<2>
  DQS2_B_C  = M_B_CPU0_SB_DQS_DN<2>
  VSS56  = GND
  DQ20_B  = M_B_CPU0_SB_DQ<20>
  VSS57  = GND
  DQ21_B  = M_B_CPU0_SB_DQ<21>
  VSS58  = GND
  DQ24_B  = M_B_CPU0_SB_DQ<24>
  VSS59  = GND
  DQ25_B  = M_B_CPU0_SB_DQ<25>
  VSS60  = GND
  DQS3_B_T  = M_B_CPU0_SB_DQS_DP<3>
  DQS3_B_C  = M_B_CPU0_SB_DQS_DN<3>
  VSS61  = GND
  DQ28_B  = M_B_CPU0_SB_DQ<28>
  VSS62  = GND
  DQ29_B  = M_B_CPU0_SB_DQ<29>
  VSS63  = GND
  RFU1  = NC
  VIN_BULK1  = P12V_MEM_CPU0
  VIN_BULK2  = P12V_MEM_CPU0
  \pwr_good||fail_n\  = PWRGD_CHB_CPU0_DIMM
  HAS  = PD_CHB_CPU0_DIMM_SAA
  RFU2  = NC
  RFU3  = NC
  VSS64  = GND
  DQ2_A  = M_B_CPU0_SA_DQ<2>
  VSS65  = GND
  DQ3_A  = M_B_CPU0_SA_DQ<3>
  VSS66  = GND
  \dqs5_a_c||tdqs5_a_c||dqs5_a_t||tdqs5_a_t\  = M_B_CPU0_SA_DQS_DN<5>
  \dqs5_a_t||tdqs5_a_t\  = M_B_CPU0_SA_DQS_DP<5>
  VSS67  = GND
  DQ6_A  = M_B_CPU0_SA_DQ<6>
  VSS68  = GND
  DQ7_A  = M_B_CPU0_SA_DQ<7>
  VSS69  = GND
  DQ10_A  = M_B_CPU0_SA_DQ<10>
  VSS70  = GND
  DQ11_A  = M_B_CPU0_SA_DQ<11>
  VSS71  = GND
  \dqs6_a_c||tdqs6_a_c||dqs6_a_t||tdqs6_a_t\  = M_B_CPU0_SA_DQS_DN<6>
  \dqs6_a_t||tdqs6_a_t\  = M_B_CPU0_SA_DQS_DP<6>
  VSS72  = GND
  DQ14_A  = M_B_CPU0_SA_DQ<14>
  VSS73  = GND
  DQ15_A  = M_B_CPU0_SA_DQ<15>
  VSS74  = GND
  DQ18_A  = M_B_CPU0_SA_DQ<18>
  VSS75  = GND
  DQ19_A  = M_B_CPU0_SA_DQ<19>
  VSS76  = GND
  \dqs7_a_c||tdqs7_a_c\  = M_B_CPU0_SA_DQS_DN<7>
  \dqs7_a_t||tdqs7_a_t\  = M_B_CPU0_SA_DQS_DP<7>
  VSS77  = GND
  DQ22_A  = M_B_CPU0_SA_DQ<22>
  VSS78  = GND
  DQ23_A  = M_B_CPU0_SA_DQ<23>
  VSS79  = GND
  DQ26_A  = M_B_CPU0_SA_DQ<26>
  VSS80  = GND
  DQ27_A  = M_B_CPU0_SA_DQ<27>
  VSS81  = GND
  \dqs8_a_c||tdqs8_a_c\  = M_B_CPU0_SA_DQS_DN<8>
  \dqs8_a_t||tdqs8_a_t\  = M_B_CPU0_SA_DQS_DP<8>
  VSS82  = GND
  DQ30_A  = M_B_CPU0_SA_DQ<30>
  VSS83  = GND
  DQ31_A  = M_B_CPU0_SA_DQ<31>
  VSS84  = GND
  CB2_A  = M_B_CPU0_SA_CB<2>
  VSS85  = GND
  CB3_A  = M_B_CPU0_SA_CB<3>
  VSS86  = GND
  \dqs9_a_c||tdqs9_a_c\  = M_B_CPU0_SA_DQS_DN<9>
  \dqs9_a_t||tdqs9_a_t\  = M_B_CPU0_SA_DQS_DP<9>
  VSS87  = GND
  CB6_A  = M_B_CPU0_SA_CB<6>
  VSS88  = GND
  CB7_A  = M_B_CPU0_SA_CB<7>
  VSS89  = GND
  RESET_N  = M_B_CPU0_RESET_N
  VSS90  = GND
  CS1_A_N  = M_B_CPU0_SA_CS_N<1>
  VSS91  = GND
  CA1_A  = M_B_CPU0_SA_CA<1>
  VSS92  = GND
  CA3_A  = M_B_CPU0_SA_CA<3>
  VSS93  = GND
  CA5_A  = M_B_CPU0_SA_CA<5>
  VSS94  = GND
  CK_T  = M_B_CPU0_CLK_DP<0>
  CK_C  = M_B_CPU0_CLK_DN<0>
  VSS95  = GND
  RFU4  = NC
  CA1_B  = M_B_CPU0_SB_CA<1>
  VSS96  = GND
  CA3_B  = M_B_CPU0_SB_CA<3>
  VSS97  = GND
  CA5_B  = M_B_CPU0_SB_CA<5>
  VSS98  = GND
  PAR_B  = M_B_CPU0_SB_PAR
  VSS99  = GND
  CS1_B_N  = M_B_CPU0_SB_CS_N<1>
  VSS100  = GND
  RFU5  = NC
  RFU6  = NC
  VSS101  = GND
  CB6_B  = M_B_CPU0_SB_CB<6>
  VSS102  = GND
  CB7_B  = M_B_CPU0_SB_CB<7>
  VSS103  = GND
  DQS4_B_C  = M_B_CPU0_SB_DQS_DN<4>
  DQS4_B_T  = M_B_CPU0_SB_DQS_DP<4>
  VSS104  = GND
  CB2_B  = M_B_CPU0_SB_CB<2>
  VSS105  = GND
  CB3_B  = M_B_CPU0_SB_CB<3>
  VSS106  = GND
  DQ2_B  = M_B_CPU0_SB_DQ<2>
  VSS107  = GND
  DQ3_B  = M_B_CPU0_SB_DQ<3>
  VSS108  = GND
  \dqs5_b_c||tdqs5_b_c\  = M_B_CPU0_SB_DQS_DN<5>
  \dqs5_b_t||tdqs5_b_t\  = M_B_CPU0_SB_DQS_DP<5>
  VSS109  = GND
  DQ6_B  = M_B_CPU0_SB_DQ<6>
  VSS110  = GND
  DQ7_B  = M_B_CPU0_SB_DQ<7>
  VSS111  = GND
  DQ10_B  = M_B_CPU0_SB_DQ<10>
  VSS112  = GND
  DQ11_B  = M_B_CPU0_SB_DQ<11>
  VSS113  = GND
  \dqs6_b_c||tdqs6_b_c\  = M_B_CPU0_SB_DQS_DN<6>
  \dqs6_b_t||tdqs6_b_t\  = M_B_CPU0_SB_DQS_DP<6>
  VSS114  = GND
  DQ14_B  = M_B_CPU0_SB_DQ<14>
  VSS115  = GND
  DQ15_B  = M_B_CPU0_SB_DQ<15>
  VSS116  = GND
  DQ18_B  = M_B_CPU0_SB_DQ<18>
  VSS117  = GND
  DQ19_B  = M_B_CPU0_SB_DQ<19>
  VSS118  = GND
  \dqs7_b_c||tdqs7_b_c\  = M_B_CPU0_SB_DQS_DN<7>
  \dqs7_b_t||tdqs7_b_t\  = M_B_CPU0_SB_DQS_DP<7>
  VSS119  = GND
  DQ22_B  = M_B_CPU0_SB_DQ<22>
  VSS120  = GND
  DQ23_B  = M_B_CPU0_SB_DQ<23>
  VSS121  = GND
  DQ26_B  = M_B_CPU0_SB_DQ<26>
  VSS122  = GND
  DQ27_B  = M_B_CPU0_SB_DQ<27>
  VSS123  = GND
  \dqs8_b_c||tdqs8_b_c\  = M_B_CPU0_SB_DQS_DN<8>
  \dqs8_b_t||tdqs8_b_t\  = M_B_CPU0_SB_DQS_DP<8>
  VSS124  = GND
  DQ30_B  = M_B_CPU0_SB_DQ<30>
  VSS125  = GND
  DQ31_B  = M_B_CPU0_SB_DQ<31>
  VSS126  = GND
  G1  = GND
  G2  = GND
  G3  = GND

(kicad_pcb
	(version 20260206)
	(generator "pcbnew")
	(generator_version "10.0")
	(general
		(thickness 1.6)
		(legacy_teardrops no)
	)
	(paper "A4")
	(title_block
		(title "04192023_DAF0TMB3IC0_F0TG_MB_C_brd_V02_OCP.brd")
		(comment 1 "Grand Teton / footprint 1120 of 8354 (J15), pads 1-46 of 291")
	)
	(layers
		(0 "F.Cu" signal "TOP")
		(4 "In1.Cu" signal "GND")
		(6 "In2.Cu" signal "IN1")
		(8 "In3.Cu" signal "GND1")
		(10 "In4.Cu" signal "IN2")
		(12 "In5.Cu" signal "GND2")
		(14 "In6.Cu" signal "IN3")
		(16 "In7.Cu" signal "GND3")
		(18 "In8.Cu" signal "VCC")
		(20 "In9.Cu" signal "VCC1")
		(22 "In10.Cu" signal "GND4")
		(24 "In11.Cu" signal "IN4")
		(26 "In12.Cu" signal "GND5")
		(28 "In13.Cu" signal "IN5")
		(30 "In14.Cu" signal "GND6")
		(32 "In15.Cu" signal "IN6")
		(34 "In16.Cu" signal "GND7")
		(2 "B.Cu" signal "BOTTOM")
		(9 "F.Adhes" user "F.Adhesive")
		(11 "B.Adhes" user "B.Adhesive")
		(13 "F.Paste" user "Package Geometry/Pastemask Top")
		(15 "B.Paste" user "Package Geometry/Pastemask Bottom")
		(5 "F.SilkS" user "Ref Des/Silkscreen Top")
		(7 "B.SilkS" user "Ref Des/Silkscreen Bottom")
		(1 "F.Mask" user "Board Geometry/Soldermask Top")
		(3 "B.Mask" user "Board Geometry/Soldermask Bottom")
		(17 "Dwgs.User" user "User.Drawings")
		(19 "Cmts.User" user "User.Comments")
		(21 "Eco1.User" user "User.Eco1")
		(23 "Eco2.User" user "User.Eco2")
		(25 "Edge.Cuts" user "Board Geometry/Outline")
		(27 "Margin" user)
		(31 "F.CrtYd" user "Package Geometry/Place Bound Top")
		(29 "B.CrtYd" user "Package Geometry/Place Bound Bottom")
		(35 "F.Fab" user "Ref Des/Assembly Top")
		(33 "B.Fab" user "Ref Des/Assembly Bottom")
	)
	(footprint ""
		(layer "F.Cu")
		(at 297.774106 -255.560068 180)
		(property "Reference" "J15"
			(at -2.2098 -81.984088 0)
			(unlocked yes)
			(layer "F.SilkS")
			(effects
				(font
					(size 0.7874 0.5842)
					(thickness 0.1524)
				)
			)
		)
		(property "Value" ""
			(at 0 0 180)
			(layer "F.Fab")
			(effects
				(font
					(size 1.27 1.27)
				)
			)
		)
		(duplicate_pad_numbers_are_jumpers no)
		(pad "1" smd rect
			(at -2.050034 -63.324994 90)
			(size 0.519938 1.4986)
			(layers "F.Cu" "F.Mask" "F.Paste")
			(net "P12V_MEM_CPU0")
		)
		(pad "2" smd rect
			(at -2.050034 -62.47511 90)
			(size 0.519938 1.4986)
			(layers "F.Cu" "F.Mask" "F.Paste")
			(net "Net_2263")
		)
		(pad "3" smd rect
			(at -2.050034 -61.624972 90)
			(size 0.519938 1.4986)
			(layers "F.Cu" "F.Mask" "F.Paste")
			(net "P3V3_AUX")
		)
		(pad "4" smd rect
			(at -2.050034 -60.775088 90)
			(size 0.519938 1.4986)
			(layers "F.Cu" "F.Mask" "F.Paste")
			(net "I3C_SPD_DDRB_CPU0_SCL")
		)
		(pad "5" smd rect
			(at -2.050034 -59.92495 90)
			(size 0.519938 1.4986)
			(layers "F.Cu" "F.Mask" "F.Paste")
			(net "I3C_SPD_DDRB_CPU0_SDA")
		)
		(pad "6" smd rect
			(at -2.050034 -59.075066 90)
			(size 0.519938 1.4986)
			(layers "F.Cu" "F.Mask" "F.Paste")
			(net "GND")
		)
		(pad "7" smd rect
			(at -2.050034 -58.224928 90)
			(size 0.519938 1.4986)
			(layers "F.Cu" "F.Mask" "F.Paste")
			(net "M_B_CPU0_SA_DQ<0>")
		)
		(pad "8" smd rect
			(at -2.050034 -57.375044 90)
			(size 0.519938 1.4986)
			(layers "F.Cu" "F.Mask" "F.Paste")
			(net "GND")
		)
		(pad "9" smd rect
			(at -2.050034 -56.524906 90)
			(size 0.519938 1.4986)
			(layers "F.Cu" "F.Mask" "F.Paste")
			(net "M_B_CPU0_SA_DQ<1>")
		)
		(pad "10" smd rect
			(at -2.050034 -55.675022 90)
			(size 0.519938 1.4986)
			(layers "F.Cu" "F.Mask" "F.Paste")
			(net "GND")
		)
		(pad "11" smd rect
			(at -2.050034 -54.824884 90)
			(size 0.519938 1.4986)
			(layers "F.Cu" "F.Mask" "F.Paste")
			(net "M_B_CPU0_SA_DQS_DP<0>")
		)
		(pad "12" smd rect
			(at -2.050034 -53.975 90)
			(size 0.519938 1.4986)
			(layers "F.Cu" "F.Mask" "F.Paste")
			(net "M_B_CPU0_SA_DQS_DN<0>")
		)
		(pad "13" smd rect
			(at -2.050034 -53.125116 90)
			(size 0.519938 1.4986)
			(layers "F.Cu" "F.Mask" "F.Paste")
			(net "GND")
		)
		(pad "14" smd rect
			(at -2.050034 -52.274978 90)
			(size 0.519938 1.4986)
			(layers "F.Cu" "F.Mask" "F.Paste")
			(net "M_B_CPU0_SA_DQ<4>")
		)
		(pad "15" smd rect
			(at -2.050034 -51.425094 90)
			(size 0.519938 1.4986)
			(layers "F.Cu" "F.Mask" "F.Paste")
			(net "GND")
		)
		(pad "16" smd rect
			(at -2.050034 -50.574956 90)
			(size 0.519938 1.4986)
			(layers "F.Cu" "F.Mask" "F.Paste")
			(net "M_B_CPU0_SA_DQ<5>")
		)
		(pad "17" smd rect
			(at -2.050034 -49.725072 90)
			(size 0.519938 1.4986)
			(layers "F.Cu" "F.Mask" "F.Paste")
			(net "GND")
		)
		(pad "18" smd rect
			(at -2.050034 -48.874934 90)
			(size 0.519938 1.4986)
			(layers "F.Cu" "F.Mask" "F.Paste")
			(net "M_B_CPU0_SA_DQ<8>")
		)
		(pad "19" smd rect
			(at -2.050034 -48.02505 90)
			(size 0.519938 1.4986)
			(layers "F.Cu" "F.Mask" "F.Paste")
			(net "GND")
		)
		(pad "20" smd rect
			(at -2.050034 -47.174912 90)
			(size 0.519938 1.4986)
			(layers "F.Cu" "F.Mask" "F.Paste")
			(net "M_B_CPU0_SA_DQ<9>")
		)
		(pad "21" smd rect
			(at -2.050034 -46.325028 90)
			(size 0.519938 1.4986)
			(layers "F.Cu" "F.Mask" "F.Paste")
			(net "GND")
		)
		(pad "22" smd rect
			(at -2.050034 -45.47489 90)
			(size 0.519938 1.4986)
			(layers "F.Cu" "F.Mask" "F.Paste")
			(net "M_B_CPU0_SA_DQS_DP<1>")
		)
		(pad "23" smd rect
			(at -2.050034 -44.625006 90)
			(size 0.519938 1.4986)
			(layers "F.Cu" "F.Mask" "F.Paste")
			(net "M_B_CPU0_SA_DQS_DN<1>")
		)
		(pad "24" smd rect
			(at -2.050034 -43.775122 90)
			(size 0.519938 1.4986)
			(layers "F.Cu" "F.Mask" "F.Paste")
			(net "GND")
		)
		(pad "25" smd rect
			(at -2.050034 -42.924984 90)
			(size 0.519938 1.4986)
			(layers "F.Cu" "F.Mask" "F.Paste")
			(net "M_B_CPU0_SA_DQ<12>")
		)
		(pad "26" smd rect
			(at -2.050034 -42.0751 90)
			(size 0.519938 1.4986)
			(layers "F.Cu" "F.Mask" "F.Paste")
			(net "GND")
		)
		(pad "27" smd rect
			(at -2.050034 -41.224962 90)
			(size 0.519938 1.4986)
			(layers "F.Cu" "F.Mask" "F.Paste")
			(net "M_B_CPU0_SA_DQ<13>")
		)
		(pad "28" smd rect
			(at -2.050034 -40.375078 90)
			(size 0.519938 1.4986)
			(layers "F.Cu" "F.Mask" "F.Paste")
			(net "GND")
		)
		(pad "29" smd rect
			(at -2.050034 -39.52494 90)
			(size 0.519938 1.4986)
			(layers "F.Cu" "F.Mask" "F.Paste")
			(net "M_B_CPU0_SA_DQ<16>")
		)
		(pad "30" smd rect
			(at -2.050034 -38.675056 90)
			(size 0.519938 1.4986)
			(layers "F.Cu" "F.Mask" "F.Paste")
			(net "GND")
		)
		(pad "31" smd rect
			(at -2.050034 -37.824918 90)
			(size 0.519938 1.4986)
			(layers "F.Cu" "F.Mask" "F.Paste")
			(net "M_B_CPU0_SA_DQ<17>")
		)
		(pad "32" smd rect
			(at -2.050034 -36.975034 90)
			(size 0.519938 1.4986)
			(layers "F.Cu" "F.Mask" "F.Paste")
			(net "GND")
		)
		(pad "33" smd rect
			(at -2.050034 -36.124896 90)
			(size 0.519938 1.4986)
			(layers "F.Cu" "F.Mask" "F.Paste")
			(net "M_B_CPU0_SA_DQS_DP<2>")
		)
		(pad "34" smd rect
			(at -2.050034 -35.275012 90)
			(size 0.519938 1.4986)
			(layers "F.Cu" "F.Mask" "F.Paste")
			(net "M_B_CPU0_SA_DQS_DN<2>")
		)
		(pad "35" smd rect
			(at -2.050034 -34.425128 90)
			(size 0.519938 1.4986)
			(layers "F.Cu" "F.Mask" "F.Paste")
			(net "GND")
		)
		(pad "36" smd rect
			(at -2.050034 -33.57499 90)
			(size 0.519938 1.4986)
			(layers "F.Cu" "F.Mask" "F.Paste")
			(net "M_B_CPU0_SA_DQ<20>")
		)
		(pad "37" smd rect
			(at -2.050034 -32.725106 90)
			(size 0.519938 1.4986)
			(layers "F.Cu" "F.Mask" "F.Paste")
			(net "GND")
		)
		(pad "38" smd rect
			(at -2.050034 -31.874968 90)
			(size 0.519938 1.4986)
			(layers "F.Cu" "F.Mask" "F.Paste")
			(net "M_B_CPU0_SA_DQ<21>")
		)
		(pad "39" smd rect
			(at -2.050034 -31.025084 90)
			(size 0.519938 1.4986)
			(layers "F.Cu" "F.Mask" "F.Paste")
			(net "GND")
		)
		(pad "40" smd rect
			(at -2.050034 -30.174946 90)
			(size 0.519938 1.4986)
			(layers "F.Cu" "F.Mask" "F.Paste")
			(net "M_B_CPU0_SA_DQ<24>")
		)
		(pad "41" smd rect
			(at -2.050034 -29.325062 90)
			(size 0.519938 1.4986)
			(layers "F.Cu" "F.Mask" "F.Paste")
			(net "GND")
		)
		(pad "42" smd rect
			(at -2.050034 -28.474924 90)
			(size 0.519938 1.4986)
			(layers "F.Cu" "F.Mask" "F.Paste")
			(net "M_B_CPU0_SA_DQ<25>")
		)
		(pad "43" smd rect
			(at -2.050034 -27.62504 90)
			(size 0.519938 1.4986)
			(layers "F.Cu" "F.Mask" "F.Paste")
			(net "GND")
		)
		(pad "44" smd rect
			(at -2.050034 -26.774902 90)
			(size 0.519938 1.4986)
			(layers "F.Cu" "F.Mask" "F.Paste")
			(net "M_B_CPU0_SA_DQS_DP<3>")
		)
		(pad "45" smd rect
			(at -2.050034 -25.925018 90)
			(size 0.519938 1.4986)
			(layers "F.Cu" "F.Mask" "F.Paste")
			(net "M_B_CPU0_SA_DQS_DN<3>")
		)
		(pad "46" smd rect
			(at -2.050034 -25.07488 90)
			(size 0.519938 1.4986)
			(layers "F.Cu" "F.Mask" "F.Paste")
			(net "GND")
		)
	)
)
